# S9S_MB_2U (Grand Teton) — schematic netlist excerpt (pin names and nets, part order shuffled) for the footprints in the layout excerpt that follows; sources: Cadence DE-HDL packaged netlist, KiCad conversion of 03242023_DA0F0TMBIJ0_F0T_Motherboard_J_brd_V01_OCP.brd

R3601  Q_RES  33.2 1% CHIP  pkg 0402LF  page 171 : A = SMB_INA230_1_3V3AUX_SDA_R ; B = SMB_INA230_1_3V3AUX_SDA_R1

(kicad_pcb
	(version 20260206)
	(generator "pcbnew")
	(generator_version "10.0")
	(general
		(thickness 1.6)
		(legacy_teardrops no)
	)
	(paper "A4")
	(title_block
		(title "03242023_DA0F0TMBIJ0_F0T_Motherboard_J_brd_V01_OCP.brd")
		(comment 1 "Grand Teton / footprints 4132-4132 of 6105")
	)
	(layers
		(0 "F.Cu" signal "TOP")
		(4 "In1.Cu" signal "GND")
		(6 "In2.Cu" signal "IN1")
		(8 "In3.Cu" signal "GND1")
		(10 "In4.Cu" signal "IN2")
		(12 "In5.Cu" signal "GND2")
		(14 "In6.Cu" signal "IN3")
		(16 "In7.Cu" signal "GND3")
		(18 "In8.Cu" signal "VCC")
		(20 "In9.Cu" signal "VCC1")
		(22 "In10.Cu" signal "GND4")
		(24 "In11.Cu" signal "IN4")
		(26 "In12.Cu" signal "GND5")
		(28 "In13.Cu" signal "IN5")
		(30 "In14.Cu" signal "GND6")
		(32 "In15.Cu" signal "IN6")
		(34 "In16.Cu" signal "GND7")
		(2 "B.Cu" signal "BOTTOM")
		(9 "F.Adhes" user "F.Adhesive")
		(11 "B.Adhes" user "B.Adhesive")
		(13 "F.Paste" user "Package Geometry/Pastemask Top")
		(15 "B.Paste" user "Package Geometry/Pastemask Bottom")
		(5 "F.SilkS" user "Ref Des/Silkscreen Top")
		(7 "B.SilkS" user "Ref Des/Silkscreen Bottom")
		(1 "F.Mask" user "Board Geometry/Soldermask Top")
		(3 "B.Mask" user "Board Geometry/Soldermask Bottom")
		(17 "Dwgs.User" user "User.Drawings")
		(19 "Cmts.User" user "User.Comments")
		(21 "Eco1.User" user "User.Eco1")
		(23 "Eco2.User" user "User.Eco2")
		(25 "Edge.Cuts" user "Board Geometry/Outline")
		(27 "Margin" user)
		(31 "F.CrtYd" user "Package Geometry/Place Bound Top")
		(29 "B.CrtYd" user "Package Geometry/Place Bound Bottom")
		(35 "F.Fab" user "Ref Des/Assembly Top")
		(33 "B.Fab" user "Ref Des/Assembly Bottom")
	)
	(footprint ""
		(layer "F.Cu")
		(at 445.19088 -95.872808 180)
		(property "Reference" "R3601"
			(at 0 0 180)
			(layer "F.SilkS")
			(hide yes)
			(effects
				(font
					(size 1.27 1.27)
				)
			)
		)
		(property "Value" ""
			(at 0 0 180)
			(layer "F.Fab")
			(effects
				(font
					(size 1.27 1.27)
				)
			)
		)
		(duplicate_pad_numbers_are_jumpers no)
		(fp_line
			(start 0.7874 0.4064)
			(end -0.7874 0.4064)
			(stroke
				(width 0.1524)
				(type default)
			)
			(layer "F.SilkS")
		)
		(fp_line
			(start 0.7874 -0.4064)
			(end 0.7874 0.4064)
			(stroke
				(width 0.1524)
				(type default)
			)
			(layer "F.SilkS")
		)
		(fp_line
			(start -0.7874 0.4064)
			(end -0.7874 -0.4064)
			(stroke
				(width 0.1524)
				(type default)
			)
			(layer "F.SilkS")
		)
		(fp_line
			(start -0.7874 -0.4064)
			(end 0.7874 -0.4064)
			(stroke
				(width 0.1524)
				(type default)
			)
			(layer "F.SilkS")
		)
		(fp_line
			(start 0.67945 0.3048)
			(end 0.120396 0.3048)
			(stroke
				(width 0.1)
				(type default)
			)
			(layer "F.Fab")
		)
		(fp_line
			(start 0.67945 -0.3048)
			(end 0.67945 0.3048)
			(stroke
				(width 0.1)
				(type default)
			)
			(layer "F.Fab")
		)
		(fp_line
			(start 0.12065 -0.2794)
			(end 0.12065 -0.3048)
			(stroke
				(width 0.1)
				(type default)
			)
			(layer "F.Fab")
		)
		(fp_line
			(start 0.12065 -0.3048)
			(end 0.67945 -0.3048)
			(stroke
				(width 0.1)
				(type default)
			)
			(layer "F.Fab")
		)
		(fp_line
			(start 0.120396 0.3048)
			(end 0.120396 0.2794)
			(stroke
				(width 0.1)
				(type default)
			)
			(layer "F.Fab")
		)
		(fp_line
			(start 0.120396 0.2794)
			(end -0.12065 0.2794)
			(stroke
				(width 0.1)
				(type default)
			)
			(layer "F.Fab")
		)
		(fp_line
			(start -0.12065 0.3048)
			(end -0.67945 0.3048)
			(stroke
				(width 0.1)
				(type default)
			)
			(layer "F.Fab")
		)
		(fp_line
			(start -0.12065 0.2794)
			(end -0.12065 0.3048)
			(stroke
				(width 0.1)
				(type default)
			)
			(layer "F.Fab")
		)
		(fp_line
			(start -0.12065 -0.2794)
			(end 0.12065 -0.2794)
			(stroke
				(width 0.1)
				(type default)
			)
			(layer "F.Fab")
		)
		(fp_line
			(start -0.12065 -0.305054)
			(end -0.12065 -0.2794)
			(stroke
				(width 0.1)
				(type default)
			)
			(layer "F.Fab")
		)
		(fp_line
			(start -0.67945 0.3048)
			(end -0.67945 -0.305054)
			(stroke
				(width 0.1)
				(type default)
			)
			(layer "F.Fab")
		)
		(fp_line
			(start -0.67945 -0.305054)
			(end -0.12065 -0.305054)
			(stroke
				(width 0.1)
				(type default)
			)
			(layer "F.Fab")
		)
		(pad "1" smd circle
			(at -0.40005 0 180)
			(size 0 0)
			(layers "F.Cu" "F.Mask" "F.Paste")
			(net "SMB_INA230_1_3V3AUX_SDA_R")
		)
		(pad "2" smd circle
			(at 0.40005 0 180)
			(size 0 0)
			(layers "F.Cu" "F.Mask" "F.Paste")
			(net "SMB_INA230_1_3V3AUX_SDA_R1")
		)
	)
)
